(kicad_pcb
	(version 20241229)
	(generator "pcbnew")
	(generator_version "9.0")
	(general
		(thickness 1.6642)
		(legacy_teardrops no)
	)
	(paper "A3")
	(title_block
		(title "PolarFire SoM")
		(date "2025-07-22")
		(rev "1.1.4")
		(company "Antmicro Ltd")
		(comment 1 "www.antmicro.com")
		(comment 9 "footprints 174-177 of 470")
	)
	(layers
		(0 "F.Cu" mixed)
		(4 "In1.Cu" power)
		(6 "In2.Cu" signal)
		(8 "In3.Cu" power)
		(10 "In4.Cu" signal)
		(12 "In5.Cu" power)
		(14 "In6.Cu" power)
		(16 "In7.Cu" signal)
		(18 "In8.Cu" power)
		(20 "In9.Cu" signal)
		(22 "In10.Cu" power)
		(24 "In11.Cu" signal)
		(26 "In12.Cu" signal)
		(2 "B.Cu" mixed)
		(9 "F.Adhes" user "F.Adhesive")
		(11 "B.Adhes" user "B.Adhesive")
		(13 "F.Paste" user)
		(15 "B.Paste" user)
		(5 "F.SilkS" user "F.Silkscreen")
		(7 "B.SilkS" user "B.Silkscreen")
		(1 "F.Mask" user)
		(3 "B.Mask" user)
		(17 "Dwgs.User" user "User.Drawings")
		(19 "Cmts.User" user "User.Comments")
		(21 "Eco1.User" user "User.Eco1")
		(23 "Eco2.User" user "User.Eco2")
		(25 "Edge.Cuts" user)
		(27 "Margin" user)
		(31 "F.CrtYd" user "F.Courtyard")
		(29 "B.CrtYd" user "B.Courtyard")
		(35 "F.Fab" user)
		(33 "B.Fab" user)
	)
	(footprint "antmicro-footprints:C_0402_1005Metric"
		(layer "B.Cu")
		(at 201.15 140.564 90)
		(descr "Capacitor SMD 0402")
		(tags "capacitor SMD 0402")
		(property "Reference" "C27"
			(at 0.424 2.72 270)
			(layer "B.SilkS")
			(effects
				(font
					(size 0.7 0.7)
					(thickness 0.15)
				)
				(justify left bottom mirror)
			)
		)
		(property "Value" "C_4n7_0402"
			(at -1.022927 -2.155213 270)
			(layer "B.Fab")
			(hide yes)
			(effects
				(font
					(size 0.7 0.7)
					(thickness 0.15)
				)
				(justify left bottom mirror)
			)
		)
		(property "Datasheet" "https://product.tdk.com/en/search/capacitor/ceramic/mlcc/info?part_no=CGA2B3X7S2A472K050BB"
			(at 0 0 90)
			(layer "F.Fab")
			(hide yes)
			(effects
				(font
					(size 1.27 1.27)
					(thickness 0.15)
				)
			)
		)
		(property "Description" "SMD Multilayer Ceramic Capacitor, 4700 pF, 100 V, 0402 [1005 Metric], ± 10%, X7S, CGA"
			(at 0 0 90)
			(layer "F.Fab")
			(hide yes)
			(effects
				(font
					(size 1.27 1.27)
					(thickness 0.15)
				)
			)
		)
		(property "Author" "Antmicro"
			(at 341.714 -60.586 0)
			(layer "B.Fab")
			(hide yes)
			(effects
				(font
					(size 1 1)
					(thickness 0.15)
				)
				(justify mirror)
			)
		)
		(property "Dielectric" "X7R"
			(at 341.714 -60.586 0)
			(layer "B.Fab")
			(hide yes)
			(effects
				(font
					(size 1 1)
					(thickness 0.15)
				)
				(justify mirror)
			)
		)
		(property "License" "Apache-2.0"
			(at 341.714 -60.586 0)
			(layer "B.Fab")
			(hide yes)
			(effects
				(font
					(size 1 1)
					(thickness 0.15)
				)
				(justify mirror)
			)
		)
		(property "MPN" "CGA2B3X7S2A472K050BB"
			(at 341.714 -60.586 0)
			(layer "B.Fab")
			(hide yes)
			(effects
				(font
					(size 1 1)
					(thickness 0.15)
				)
				(justify mirror)
			)
		)
		(property "Manufacturer" "TDK"
			(at 341.714 -60.586 0)
			(layer "B.Fab")
			(hide yes)
			(effects
				(font
					(size 1 1)
					(thickness 0.15)
				)
				(justify mirror)
			)
		)
		(property "Public" ""
			(at 341.714 -60.586 0)
			(layer "B.Fab")
			(hide yes)
			(effects
				(font
					(size 1 1)
					(thickness 0.15)
				)
				(justify mirror)
			)
		)
		(property "Val" "4n7"
			(at 341.714 -60.586 0)
			(layer "B.Fab")
			(hide yes)
			(effects
				(font
					(size 1 1)
					(thickness 0.15)
				)
				(justify mirror)
			)
		)
		(property "Voltage" "25V"
			(at 341.714 -60.586 0)
			(layer "B.Fab")
			(hide yes)
			(effects
				(font
					(size 1 1)
					(thickness 0.15)
				)
				(justify mirror)
			)
		)
		(sheetname "/FPGA Supply/")
		(sheetfile "fpga-supply.kicad_sch")
		(attr smd)
		(fp_rect
			(start -0.925 0.47)
			(end 0.925 -0.47)
			(stroke
				(width 0.05)
				(type default)
			)
			(fill no)
			(layer "B.CrtYd")
		)
		(fp_line
			(start 0.504 -0.248)
			(end -0.494 -0.248)
			(stroke
				(width 0.15)
				(type solid)
			)
			(layer "B.Fab")
		)
		(fp_line
			(start -0.494 -0.248)
			(end -0.494 0.25)
			(stroke
				(width 0.15)
				(type solid)
			)
			(layer "B.Fab")
		)
		(fp_line
			(start 0.504 0.25)
			(end 0.504 -0.248)
			(stroke
				(width 0.15)
				(type solid)
			)
			(layer "B.Fab")
		)
		(fp_line
			(start -0.494 0.25)
			(end 0.504 0.25)
			(stroke
				(width 0.15)
				(type solid)
			)
			(layer "B.Fab")
		)
		(fp_text user "Author: Antmicro"
			(at -0.939 -3.399 270)
			(layer "B.Fab")
			(effects
				(font
					(size 0.7 0.7)
					(thickness 0.15)
				)
				(justify left bottom mirror)
			)
		)
		(fp_text user "License: Apache-2.0"
			(at -0.939 -5.799 270)
			(layer "B.Fab")
			(effects
				(font
					(size 0.7 0.7)
					(thickness 0.15)
				)
				(justify left bottom mirror)
			)
		)
		(fp_text user "${REFERENCE}"
			(at -0.939 -4.599 270)
			(layer "B.Fab")
			(effects
				(font
					(size 0.7 0.7)
					(thickness 0.15)
				)
				(justify left bottom mirror)
			)
		)
		(pad "1" smd roundrect
			(at -0.48 0 90)
			(size 0.59 0.64)
			(layers "B.Cu" "B.Mask" "B.Paste")
			(roundrect_rratio 0.25)
			(net 417 "GND")
			(pintype "passive")
		)
		(pad "2" smd roundrect
			(at 0.48 0 90)
			(size 0.59 0.64)
			(layers "B.Cu" "B.Mask" "B.Paste")
			(roundrect_rratio 0.25)
			(net 47 "+1V05")
			(pintype "passive")
		)
	)
	(footprint "antmicro-footprints:C_0402_1005Metric"
		(layer "B.Cu")
		(at 206.146 148.65 180)
		(descr "Capacitor SMD 0402")
		(tags "capacitor SMD 0402")
		(property "Reference" "C281"
			(at -1.044 8.94 0)
			(layer "B.SilkS")
			(effects
				(font
					(size 0.7 0.7)
					(thickness 0.15)
				)
				(justify left bottom mirror)
			)
		)
		(property "Value" "C_100n_0402"
			(at -1.022927 -2.155213 0)
			(layer "B.Fab")
			(hide yes)
			(effects
				(font
					(size 0.7 0.7)
					(thickness 0.15)
				)
				(justify left bottom mirror)
			)
		)
		(property "Datasheet" "https://www.murata.com/products/productdetail?partno=GRM155R61H104KE14%23"
			(at 0 0 180)
			(layer "F.Fab")
			(hide yes)
			(effects
				(font
					(size 1.27 1.27)
					(thickness 0.15)
				)
			)
		)
		(property "Description" "SMD Multilayer Ceramic Capacitor, 0.1 µF, 50 V, 0402 [1005 Metric], ± 10%, X5R, GRM Series"
			(at 0 0 180)
			(layer "F.Fab")
			(hide yes)
			(effects
				(font
					(size 1.27 1.27)
					(thickness 0.15)
				)
			)
		)
		(property "Author" "Antmicro"
			(at 412.292 297.3 0)
			(layer "B.Fab")
			(hide yes)
			(effects
				(font
					(size 1 1)
					(thickness 0.15)
				)
				(justify mirror)
			)
		)
		(property "Dielectric" "X5R"
			(at 412.292 297.3 0)
			(layer "B.Fab")
			(hide yes)
			(effects
				(font
					(size 1 1)
					(thickness 0.15)
				)
				(justify mirror)
			)
		)
		(property "License" "Apache-2.0"
			(at 412.292 297.3 0)
			(layer "B.Fab")
			(hide yes)
			(effects
				(font
					(size 1 1)
					(thickness 0.15)
				)
				(justify mirror)
			)
		)
		(property "MPN" "GRM155R61H104KE14D"
			(at 412.292 297.3 0)
			(layer "B.Fab")
			(hide yes)
			(effects
				(font
					(size 1 1)
					(thickness 0.15)
				)
				(justify mirror)
			)
		)
		(property "Manufacturer" "Murata"
			(at 412.292 297.3 0)
			(layer "B.Fab")
			(hide yes)
			(effects
				(font
					(size 1 1)
					(thickness 0.15)
				)
				(justify mirror)
			)
		)
		(property "Public" ""
			(at 412.292 297.3 0)
			(layer "B.Fab")
			(hide yes)
			(effects
				(font
					(size 1 1)
					(thickness 0.15)
				)
				(justify mirror)
			)
		)
		(property "Val" "100n"
			(at 412.292 297.3 0)
			(layer "B.Fab")
			(hide yes)
			(effects
				(font
					(size 1 1)
					(thickness 0.15)
				)
				(justify mirror)
			)
		)
		(property "Voltage" "50V"
			(at 412.292 297.3 0)
			(layer "B.Fab")
			(hide yes)
			(effects
				(font
					(size 1 1)
					(thickness 0.15)
				)
				(justify mirror)
			)
		)
		(sheetname "/MIPI CrossLink/")
		(sheetfile "crosslink.kicad_sch")
		(attr smd)
		(fp_rect
			(start -0.925 0.47)
			(end 0.925 -0.47)
			(stroke
				(width 0.05)
				(type default)
			)
			(fill no)
			(layer "B.CrtYd")
		)
		(fp_line
			(start 0.504 0.25)
			(end 0.504 -0.248)
			(stroke
				(width 0.15)
				(type solid)
			)
			(layer "B.Fab")
		)
		(fp_line
			(start 0.504 -0.248)
			(end -0.494 -0.248)
			(stroke
				(width 0.15)
				(type solid)
			)
			(layer "B.Fab")
		)
		(fp_line
			(start -0.494 0.25)
			(end 0.504 0.25)
			(stroke
				(width 0.15)
				(type solid)
			)
			(layer "B.Fab")
		)
		(fp_line
			(start -0.494 -0.248)
			(end -0.494 0.25)
			(stroke
				(width 0.15)
				(type solid)
			)
			(layer "B.Fab")
		)
		(fp_text user "${REFERENCE}"
			(at -0.939 -4.599 0)
			(layer "B.Fab")
			(effects
				(font
					(size 0.7 0.7)
					(thickness 0.15)
				)
				(justify left bottom mirror)
			)
		)
		(fp_text user "License: Apache-2.0"
			(at -0.939 -5.799 0)
			(layer "B.Fab")
			(effects
				(font
					(size 0.7 0.7)
					(thickness 0.15)
				)
				(justify left bottom mirror)
			)
		)
		(fp_text user "Author: Antmicro"
			(at -0.939 -3.399 0)
			(layer "B.Fab")
			(effects
				(font
					(size 0.7 0.7)
					(thickness 0.15)
				)
				(justify left bottom mirror)
			)
		)
		(pad "1" smd roundrect
			(at -0.48 0 180)
			(size 0.59 0.64)
			(layers "B.Cu" "B.Mask" "B.Paste")
			(roundrect_rratio 0.25)
			(net 417 "GND")
			(pintype "passive")
		)
		(pad "2" smd roundrect
			(at 0.48 0 180)
			(size 0.59 0.64)
			(layers "B.Cu" "B.Mask" "B.Paste")
			(roundrect_rratio 0.25)
			(net 211 "/MIPI CrossLink/CL_VCCPLL_DPHY1")
			(pintype "passive")
		)
	)
	(footprint "antmicro-footprints:C_0402_1005Metric"
		(layer "B.Cu")
		(at 214.865 146.55 90)
		(descr "Capacitor SMD 0402")
		(tags "capacitor SMD 0402")
		(property "Reference" "C217"
			(at -5.56 1.65 90)
			(layer "B.SilkS")
			(effects
				(font
					(size 0.7 0.7)
					(thickness 0.15)
				)
				(justify right bottom mirror)
			)
		)
		(property "Value" "C_100n_0402"
			(at -1.022927 -2.155213 90)
			(layer "B.Fab")
			(hide yes)
			(effects
				(font
					(size 0.7 0.7)
					(thickness 0.15)
				)
				(justify right bottom mirror)
			)
		)
		(property "Datasheet" "https://www.murata.com/products/productdetail?partno=GRM155R61H104KE14%23"
			(at 0 0 90)
			(layer "F.Fab")
			(hide yes)
			(effects
				(font
					(size 1.27 1.27)
					(thickness 0.15)
				)
			)
		)
		(property "Description" "SMD Multilayer Ceramic Capacitor, 0.1 µF, 50 V, 0402 [1005 Metric], ± 10%, X5R, GRM Series"
			(at 0 0 90)
			(layer "F.Fab")
			(hide yes)
			(effects
				(font
					(size 1.27 1.27)
					(thickness 0.15)
				)
			)
		)
		(property "Author" "Antmicro"
			(at 361.415 -68.315 0)
			(layer "B.Fab")
			(hide yes)
			(effects
				(font
					(size 1 1)
					(thickness 0.15)
				)
				(justify mirror)
			)
		)
		(property "Dielectric" "X5R"
			(at 361.415 -68.315 0)
			(layer "B.Fab")
			(hide yes)
			(effects
				(font
					(size 1 1)
					(thickness 0.15)
				)
				(justify mirror)
			)
		)
		(property "License" "Apache-2.0"
			(at 361.415 -68.315 0)
			(layer "B.Fab")
			(hide yes)
			(effects
				(font
					(size 1 1)
					(thickness 0.15)
				)
				(justify mirror)
			)
		)
		(property "MPN" "GRM155R61H104KE14D"
			(at 361.415 -68.315 0)
			(layer "B.Fab")
			(hide yes)
			(effects
				(font
					(size 1 1)
					(thickness 0.15)
				)
				(justify mirror)
			)
		)
		(property "Manufacturer" "Murata"
			(at 361.415 -68.315 0)
			(layer "B.Fab")
			(hide yes)
			(effects
				(font
					(size 1 1)
					(thickness 0.15)
				)
				(justify mirror)
			)
		)
		(property "Public" ""
			(at 361.415 -68.315 0)
			(layer "B.Fab")
			(hide yes)
			(effects
				(font
					(size 1 1)
					(thickness 0.15)
				)
				(justify mirror)
			)
		)
		(property "Val" "100n"
			(at 361.415 -68.315 0)
			(layer "B.Fab")
			(hide yes)
			(effects
				(font
					(size 1 1)
					(thickness 0.15)
				)
				(justify mirror)
			)
		)
		(property "Voltage" "50V"
			(at 361.415 -68.315 0)
			(layer "B.Fab")
			(hide yes)
			(effects
				(font
					(size 1 1)
					(thickness 0.15)
				)
				(justify mirror)
			)
		)
		(sheetname "/USB/")
		(sheetfile "usb.kicad_sch")
		(attr smd)
		(fp_rect
			(start -0.925 0.47)
			(end 0.925 -0.47)
			(stroke
				(width 0.05)
				(type default)
			)
			(fill no)
			(layer "B.CrtYd")
		)
		(fp_line
			(start 0.504 -0.248)
			(end -0.494 -0.248)
			(stroke
				(width 0.15)
				(type solid)
			)
			(layer "B.Fab")
		)
		(fp_line
			(start -0.494 -0.248)
			(end -0.494 0.25)
			(stroke
				(width 0.15)
				(type solid)
			)
			(layer "B.Fab")
		)
		(fp_line
			(start 0.504 0.25)
			(end 0.504 -0.248)
			(stroke
				(width 0.15)
				(type solid)
			)
			(layer "B.Fab")
		)
		(fp_line
			(start -0.494 0.25)
			(end 0.504 0.25)
			(stroke
				(width 0.15)
				(type solid)
			)
			(layer "B.Fab")
		)
		(fp_text user "${REFERENCE}"
			(at -0.939 -4.599 270)
			(layer "B.Fab")
			(effects
				(font
					(size 0.7 0.7)
					(thickness 0.15)
				)
				(justify left bottom mirror)
			)
		)
		(fp_text user "License: Apache-2.0"
			(at -0.939 -5.799 270)
			(layer "B.Fab")
			(effects
				(font
					(size 0.7 0.7)
					(thickness 0.15)
				)
				(justify left bottom mirror)
			)
		)
		(fp_text user "Author: Antmicro"
			(at -0.939 -3.399 270)
			(layer "B.Fab")
			(effects
				(font
					(size 0.7 0.7)
					(thickness 0.15)
				)
				(justify left bottom mirror)
			)
		)
		(pad "1" smd roundrect
			(at -0.48 0 90)
			(size 0.59 0.64)
			(layers "B.Cu" "B.Mask" "B.Paste")
			(roundrect_rratio 0.25)
			(net 417 "GND")
			(pintype "passive")
		)
		(pad "2" smd roundrect
			(at 0.48 0 90)
			(size 0.59 0.64)
			(layers "B.Cu" "B.Mask" "B.Paste")
			(roundrect_rratio 0.25)
			(net 179 "Net-(U28-PLLFILT)")
			(pintype "passive")
		)
	)
	(footprint "antmicro-footprints:R_0402_1005Metric"
		(layer "B.Cu")
		(at 216.515 141.1)
		(descr "Resistor SMD 0402")
		(tags "resistor SMD 0402")
		(property "Reference" "R65"
			(at -1.075 -0.53 0)
			(layer "B.SilkS")
			(effects
				(font
					(size 0.7 0.7)
					(thickness 0.15)
				)
				(justify right bottom mirror)
			)
		)
		(property "Value" "R_27R_0402"
			(at -1.011843 -1.772047 0)
			(layer "B.Fab")
			(hide yes)
			(effects
				(font
					(size 0.7 0.7)
					(thickness 0.15)
				)
				(justify right bottom mirror)
			)
		)
		(property "Datasheet" "https://www.bourns.com/docs/product-datasheets/cr.pdf"
			(at 0 0 0)
			(layer "F.Fab")
			(hide yes)
			(effects
				(font
					(size 1.27 1.27)
					(thickness 0.15)
				)
			)
		)
		(property "Description" "SMD Chip Resistor, 27 ohm, ± 1%, 63 mW, 0402 [1005 Metric], Thick Film, General Purpose"
			(at 0 0 0)
			(layer "F.Fab")
			(hide yes)
			(effects
				(font
					(size 1.27 1.27)
					(thickness 0.15)
				)
			)
		)
		(property "Author" "Antmicro"
			(at 0 0 0)
			(layer "B.Fab")
			(hide yes)
			(effects
				(font
					(size 1 1)
					(thickness 0.15)
				)
				(justify mirror)
			)
		)
		(property "License" "Apache-2.0"
			(at 0 0 0)
			(layer "B.Fab")
			(hide yes)
			(effects
				(font
					(size 1 1)
					(thickness 0.15)
				)
				(justify mirror)
			)
		)
		(property "MPN" "CR0402-FX-27R0GLF"
			(at 0 0 0)
			(layer "B.Fab")
			(hide yes)
			(effects
				(font
					(size 1 1)
					(thickness 0.15)
				)
				(justify mirror)
			)
		)
		(property "Manufacturer" "Bourns"
			(at 0 0 0)
			(layer "B.Fab")
			(hide yes)
			(effects
				(font
					(size 1 1)
					(thickness 0.15)
				)
				(justify mirror)
			)
		)
		(property "Public" ""
			(at 0 0 0)
			(layer "B.Fab")
			(hide yes)
			(effects
				(font
					(size 1 1)
					(thickness 0.15)
				)
				(justify mirror)
			)
		)
		(property "Tolerance" "1%"
			(at 0 0 0)
			(layer "B.Fab")
			(hide yes)
			(effects
				(font
					(size 1 1)
					(thickness 0.15)
				)
				(justify mirror)
			)
		)
		(property "Val" "27R"
			(at 0 0 0)
			(layer "B.Fab")
			(hide yes)
			(effects
				(font
					(size 1 1)
					(thickness 0.15)
				)
				(justify mirror)
			)
		)
		(sheetname "/USB/")
		(sheetfile "usb.kicad_sch")
		(attr smd)
		(fp_rect
			(start -0.925 0.47)
			(end 0.925 -0.47)
			(stroke
				(width 0.05)
				(type default)
			)
			(fill no)
			(layer "B.CrtYd")
		)
		(fp_rect
			(start -0.5 0.25)
			(end 0.5 -0.25)
			(stroke
				(width 0.15)
				(type solid)
			)
			(fill no)
			(layer "B.Fab")
		)
		(fp_text user "${REFERENCE}"
			(at -0.95 -3.168 180)
			(layer "B.Fab")
			(effects
				(font
					(size 0.7 0.7)
					(thickness 0.15)
				)
				(justify left bottom mirror)
			)
		)
		(fp_text user "Author: Antmicro"
			(at -0.95 -4.169 180)
			(layer "B.Fab")
			(effects
				(font
					(size 0.7 0.7)
					(thickness 0.15)
				)
				(justify left bottom mirror)
			)
		)
		(fp_text user "License: Apache-2.0"
			(at -0.95 -5.169 180)
			(layer "B.Fab")
			(effects
				(font
					(size 0.7 0.7)
					(thickness 0.15)
				)
				(justify left bottom mirror)
			)
		)
		(pad "1" smd roundrect
			(at -0.48 0)
			(size 0.59 0.64)
			(layers "B.Cu" "B.Mask" "B.Paste")
			(roundrect_rratio 0.25)
			(net 636 "/FPGA GPIO/ULPI.CLK")
			(pintype "passive")
		)
		(pad "2" smd roundrect
			(at 0.48 0)
			(size 0.59 0.64)
			(layers "B.Cu" "B.Mask" "B.Paste")
			(roundrect_rratio 0.25)
			(net 279 "Net-(U13-CLKOUT)")
			(pintype "passive")
		)
	)
)
